(kicad_pcb
	(version 20241229)
	(generator "pcbnew")
	(generator_version "9.0")
	(general
		(thickness 1.63)
		(legacy_teardrops no)
	)
	(paper "A4")
	(title_block
		(title "CM4 Baseboard")
		(date "2026-01-05")
		(rev "1.1.1")
		(company "Antmicro Ltd")
		(comment 1 "www.antmicro.com")
		(comment 9 "footprints 108-111 of 506")
	)
	(layers
		(0 "F.Cu" signal)
		(4 "In1.Cu" power)
		(6 "In2.Cu" power)
		(8 "In3.Cu" signal)
		(10 "In4.Cu" signal)
		(2 "B.Cu" signal)
		(9 "F.Adhes" user "F.Adhesive")
		(11 "B.Adhes" user "B.Adhesive")
		(13 "F.Paste" user)
		(15 "B.Paste" user)
		(5 "F.SilkS" user "F.Silkscreen")
		(7 "B.SilkS" user "B.Silkscreen")
		(1 "F.Mask" user)
		(3 "B.Mask" user)
		(17 "Dwgs.User" user "User.Drawings")
		(19 "Cmts.User" user "User.Comments")
		(21 "Eco1.User" user "User.Eco1")
		(23 "Eco2.User" user "User.Eco2")
		(25 "Edge.Cuts" user)
		(27 "Margin" user)
		(31 "F.CrtYd" user "F.Courtyard")
		(29 "B.CrtYd" user "B.Courtyard")
		(35 "F.Fab" user)
		(33 "B.Fab" user)
	)
	(footprint "antmicro-footprints:SOT-523"
		(layer "F.Cu")
		(at 86.717962 156.6165)
		(property "Reference" "Q211"
			(at -1.2 2.13 0)
			(layer "F.SilkS")
			(effects
				(font
					(size 0.7 0.7)
					(thickness 0.15)
				)
				(justify left bottom)
			)
		)
		(property "Value" "PJE138K"
			(at 0.1 1.824 0)
			(layer "F.Fab")
			(effects
				(font
					(size 0.7 0.7)
					(thickness 0.15)
				)
				(justify left bottom)
			)
		)
		(property "Datasheet" "https://www.mouser.com/datasheet/2/1057/PJE138K-1876698.pdf"
			(at 0 0 0)
			(layer "F.Fab")
			(hide yes)
			(effects
				(font
					(size 1.27 1.27)
					(thickness 0.15)
				)
			)
		)
		(property "MPN" "PJE138K_R1_00001"
			(at 0 0 0)
			(unlocked yes)
			(layer "F.Fab")
			(hide yes)
			(effects
				(font
					(size 1 1)
					(thickness 0.15)
				)
			)
		)
		(property "Manufacturer" "PANJIT"
			(at 0 0 0)
			(unlocked yes)
			(layer "F.Fab")
			(hide yes)
			(effects
				(font
					(size 1 1)
					(thickness 0.15)
				)
			)
		)
		(property "Author" "Antmicro"
			(at 0 0 0)
			(unlocked yes)
			(layer "F.Fab")
			(hide yes)
			(effects
				(font
					(size 1 1)
					(thickness 0.15)
				)
			)
		)
		(property "License" "Apache-2.0"
			(at 0 0 0)
			(unlocked yes)
			(layer "F.Fab")
			(hide yes)
			(effects
				(font
					(size 1 1)
					(thickness 0.15)
				)
			)
		)
		(sheetname "/Compute module/")
		(sheetfile "compute-module.kicad_sch")
		(attr smd)
		(fp_line
			(start -0.927 -0.351)
			(end -0.725 -0.551)
			(stroke
				(width 0.15)
				(type solid)
			)
			(layer "F.SilkS")
		)
		(fp_line
			(start -0.927 -0.051)
			(end -0.927 -0.351)
			(stroke
				(width 0.15)
				(type solid)
			)
			(layer "F.SilkS")
		)
		(fp_line
			(start -0.725 -0.551)
			(end -0.277 -0.551)
			(stroke
				(width 0.15)
				(type solid)
			)
			(layer "F.SilkS")
		)
		(fp_line
			(start -0.277 -0.551)
			(end -0.277 -0.75)
			(stroke
				(width 0.15)
				(type solid)
			)
			(layer "F.SilkS")
		)
		(fp_circle
			(center -0.9652 0.9652)
			(end -0.9152 0.9652)
			(stroke
				(width 0.15)
				(type solid)
			)
			(fill yes)
			(layer "F.SilkS")
		)
		(fp_line
			(start -1.12 -1.16)
			(end -1.12 1.15)
			(stroke
				(width 0.05)
				(type solid)
			)
			(layer "F.CrtYd")
		)
		(fp_line
			(start -1.12 -1.16)
			(end 1.1 -1.16)
			(stroke
				(width 0.05)
				(type solid)
			)
			(layer "F.CrtYd")
		)
		(fp_line
			(start -1.12 1.15)
			(end 1.1 1.15)
			(stroke
				(width 0.05)
				(type solid)
			)
			(layer "F.CrtYd")
		)
		(fp_line
			(start 1.1 -1.16)
			(end 1.1 1.15)
			(stroke
				(width 0.05)
				(type solid)
			)
			(layer "F.CrtYd")
		)
		(fp_line
			(start -0.802 -0.276)
			(end -0.802 0.424)
			(stroke
				(width 0.15)
				(type solid)
			)
			(layer "F.Fab")
		)
		(fp_line
			(start -0.652 -0.425)
			(end -0.802 -0.276)
			(stroke
				(width 0.15)
				(type solid)
			)
			(layer "F.Fab")
		)
		(fp_line
			(start 0.8 -0.425)
			(end -0.652 -0.425)
			(stroke
				(width 0.15)
				(type solid)
			)
			(layer "F.Fab")
		)
		(fp_line
			(start 0.8 -0.425)
			(end 0.8 0.424)
			(stroke
				(width 0.15)
				(type solid)
			)
			(layer "F.Fab")
		)
		(fp_line
			(start 0.8 0.424)
			(end -0.802 0.424)
			(stroke
				(width 0.15)
				(type solid)
			)
			(layer "F.Fab")
		)
		(fp_circle
			(center -0.9652 0.9652)
			(end -0.9144 0.9652)
			(stroke
				(width 0.15)
				(type solid)
			)
			(fill no)
			(layer "F.Fab")
		)
		(fp_text user "Author: Antmicro"
			(at -1.12 6.224 0)
			(layer "F.Fab")
			(effects
				(font
					(size 0.7 0.7)
					(thickness 0.15)
				)
				(justify left bottom)
			)
		)
		(fp_text user "License: Apache-2.0"
			(at -1.12 5.024 0)
			(layer "F.Fab")
			(effects
				(font
					(size 0.7 0.7)
					(thickness 0.15)
				)
				(justify left bottom)
			)
		)
		(fp_text user "${REFERENCE}"
			(at -1.12 3.824 0)
			(layer "F.Fab")
			(effects
				(font
					(size 0.7 0.7)
					(thickness 0.15)
				)
				(justify left bottom)
			)
		)
		(pad "1" smd rect
			(at -0.5 0.65)
			(size 0.4 0.51)
			(layers "F.Cu" "F.Mask" "F.Paste")
			(net 231 "/Compute module/PolarfireID")
			(pinfunction "G")
			(pintype "input")
		)
		(pad "2" smd rect
			(at 0.498 0.65)
			(size 0.4 0.51)
			(layers "F.Cu" "F.Mask" "F.Paste")
			(net 3 "GND")
			(pinfunction "S")
			(pintype "passive")
		)
		(pad "3" smd rect
			(at 0 -0.652)
			(size 0.4 0.51)
			(layers "F.Cu" "F.Mask" "F.Paste")
			(net 444 "Net-(Q211-D)")
			(pinfunction "D")
			(pintype "passive")
		)
	)
	(footprint "antmicro-footprints:LED_0603_1608Metric_G"
		(layer "F.Cu")
		(at 75.517962 152.56 180)
		(descr "LED SMD 0603 Green")
		(tags "LED SMD 0603 Green")
		(property "Reference" "D206"
			(at -1.392038 7.46 0)
			(layer "F.SilkS")
			(effects
				(font
					(size 0.7 0.7)
					(thickness 0.15)
				)
				(justify right bottom)
			)
		)
		(property "Value" "LED_G_0603_KP-1608CGCK"
			(at -0.001 1.599 0)
			(layer "F.Fab")
			(effects
				(font
					(size 0.7 0.7)
					(thickness 0.15)
				)
				(justify right bottom)
			)
		)
		(property "Datasheet" "http://www.kingbright.com/attachments/file/psearch//000/00/00/KP-1608CGCK(Ver.23B).pdf"
			(at 0 0 180)
			(layer "F.Fab")
			(hide yes)
			(effects
				(font
					(size 1.27 1.27)
					(thickness 0.15)
				)
			)
		)
		(property "MPN" "KP-1608CGCK"
			(at 0 0 180)
			(unlocked yes)
			(layer "F.Fab")
			(hide yes)
			(effects
				(font
					(size 1 1)
					(thickness 0.15)
				)
			)
		)
		(property "Manufacturer" "Kingbright"
			(at 0 0 180)
			(unlocked yes)
			(layer "F.Fab")
			(hide yes)
			(effects
				(font
					(size 1 1)
					(thickness 0.15)
				)
			)
		)
		(property "Color" "Green"
			(at 0 0 180)
			(unlocked yes)
			(layer "F.Fab")
			(hide yes)
			(effects
				(font
					(size 1 1)
					(thickness 0.15)
				)
			)
		)
		(property "Author" "Antmicro"
			(at 0 0 180)
			(unlocked yes)
			(layer "F.Fab")
			(hide yes)
			(effects
				(font
					(size 1 1)
					(thickness 0.15)
				)
			)
		)
		(property "License" "Apache-2.0"
			(at 0 0 180)
			(unlocked yes)
			(layer "F.Fab")
			(hide yes)
			(effects
				(font
					(size 1 1)
					(thickness 0.15)
				)
			)
		)
		(sheetname "/Compute module/")
		(sheetfile "compute-module.kicad_sch")
		(attr smd)
		(fp_line
			(start 0.22 0.35)
			(end -0.22 0.35)
			(stroke
				(width 0.15)
				(type solid)
			)
			(layer "F.SilkS")
		)
		(fp_line
			(start 0.22 -0.35)
			(end -0.22 -0.35)
			(stroke
				(width 0.15)
				(type solid)
			)
			(layer "F.SilkS")
		)
		(fp_line
			(start 0.105328 0.201008)
			(end 0.105328 -0.198992)
			(stroke
				(width 0.1)
				(type solid)
			)
			(layer "F.SilkS")
		)
		(fp_line
			(start 0.105328 0.201008)
			(end -0.094672 0.001008)
			(stroke
				(width 0.1)
				(type solid)
			)
			(layer "F.SilkS")
		)
		(fp_line
			(start 0.105328 0.001008)
			(end 0.24 0.001)
			(stroke
				(width 0.1)
				(type solid)
			)
			(layer "F.SilkS")
		)
		(fp_line
			(start -0.094672 0.201008)
			(end -0.094672 -0.198992)
			(stroke
				(width 0.1)
				(type solid)
			)
			(layer "F.SilkS")
		)
		(fp_line
			(start -0.094672 0.001008)
			(end 0.105328 -0.198992)
			(stroke
				(width 0.1)
				(type solid)
			)
			(layer "F.SilkS")
		)
		(fp_line
			(start -0.094672 0.001008)
			(end -0.24 0.001008)
			(stroke
				(width 0.1)
				(type solid)
			)
			(layer "F.SilkS")
		)
		(fp_line
			(start -1.18 -0.319)
			(end -1.18 0.321)
			(stroke
				(width 0.15)
				(type solid)
			)
			(layer "F.SilkS")
		)
		(fp_rect
			(start 1.25 0.65)
			(end -1.25 -0.65)
			(stroke
				(width 0.05)
				(type solid)
			)
			(fill no)
			(layer "F.CrtYd")
		)
		(fp_line
			(start 0.599 0)
			(end 0.201 0)
			(stroke
				(width 0.15)
				(type solid)
			)
			(layer "F.Fab")
		)
		(fp_line
			(start 0.201 0.2)
			(end 0.201 0)
			(stroke
				(width 0.15)
				(type solid)
			)
			(layer "F.Fab")
		)
		(fp_line
			(start 0.201 0)
			(end 0.201 -0.202)
			(stroke
				(width 0.15)
				(type solid)
			)
			(layer "F.Fab")
		)
		(fp_line
			(start 0.201 -0.202)
			(end -0.101 0)
			(stroke
				(width 0.15)
				(type solid)
			)
			(layer "F.Fab")
		)
		(fp_line
			(start -0.101 0)
			(end 0.201 0.2)
			(stroke
				(width 0.15)
				(type solid)
			)
			(layer "F.Fab")
		)
		(fp_line
			(start -0.199 0.2)
			(end -0.199 0.1)
			(stroke
				(width 0.15)
				(type solid)
			)
			(layer "F.Fab")
		)
		(fp_line
			(start -0.199 0)
			(end -0.597 0)
			(stroke
				(width 0.15)
				(type solid)
			)
			(layer "F.Fab")
		)
		(fp_line
			(start -0.199 -0.202)
			(end -0.199 0.1)
			(stroke
				(width 0.15)
				(type solid)
			)
			(layer "F.Fab")
		)
		(fp_rect
			(start 0.848 0.4)
			(end -0.85 -0.402)
			(stroke
				(width 0.15)
				(type solid)
			)
			(fill no)
			(layer "F.Fab")
		)
		(fp_text user "${REFERENCE}"
			(at -1.4224 5.999 180)
			(layer "F.Fab")
			(effects
				(font
					(size 0.7 0.7)
					(thickness 0.15)
				)
				(justify left bottom)
			)
		)
		(fp_text user "License: Apache-2.0"
			(at -1.4224 3.599 180)
			(layer "F.Fab")
			(effects
				(font
					(size 0.7 0.7)
					(thickness 0.15)
				)
				(justify left bottom)
			)
		)
		(fp_text user "Author: Antmicro"
			(at -1.4224 4.799 180)
			(layer "F.Fab")
			(effects
				(font
					(size 0.7 0.7)
					(thickness 0.15)
				)
				(justify left bottom)
			)
		)
		(pad "1" smd roundrect
			(at -0.7 0)
			(size 0.8 1)
			(layers "F.Cu" "F.Mask" "F.Paste")
			(roundrect_rratio 0.2)
			(net 466 "Net-(D206-C)")
			(pinfunction "C")
			(pintype "passive")
		)
		(pad "2" smd roundrect
			(at 0.7 0)
			(size 0.8 1)
			(layers "F.Cu" "F.Mask" "F.Paste")
			(roundrect_rratio 0.2)
			(net 10 "+5V")
			(pinfunction "A")
			(pintype "passive")
		)
	)
	(footprint "antmicro-footprints:TP_SMD_0.75mm"
		(layer "F.Cu")
		(at 107.15 150.6)
		(property "Reference" "TP216"
			(at 0.3 0.35 0)
			(layer "F.SilkS")
			(effects
				(font
					(size 0.7 0.7)
					(thickness 0.15)
				)
				(justify left bottom)
			)
		)
		(property "Value" "TP_0.75mm_SMD"
			(at 0 1.2 0)
			(layer "F.Fab")
			(effects
				(font
					(size 0.7 0.7)
					(thickness 0.15)
				)
				(justify left bottom)
			)
		)
		(property "MPN" ""
			(at 0 0 0)
			(unlocked yes)
			(layer "F.Fab")
			(hide yes)
			(effects
				(font
					(size 1 1)
					(thickness 0.15)
				)
			)
		)
		(property "Manufacturer" ""
			(at 0 0 0)
			(unlocked yes)
			(layer "F.Fab")
			(hide yes)
			(effects
				(font
					(size 1 1)
					(thickness 0.15)
				)
			)
		)
		(property "Author" "Antmicro"
			(at 0 0 0)
			(unlocked yes)
			(layer "F.Fab")
			(hide yes)
			(effects
				(font
					(size 1 1)
					(thickness 0.15)
				)
			)
		)
		(property "License" "Apache-2.0"
			(at 0 0 0)
			(unlocked yes)
			(layer "F.Fab")
			(hide yes)
			(effects
				(font
					(size 1 1)
					(thickness 0.15)
				)
			)
		)
		(sheetname "/Compute module/")
		(sheetfile "compute-module.kicad_sch")
		(attr exclude_from_pos_files exclude_from_bom)
		(fp_circle
			(center 0 0)
			(end 0.475 0)
			(stroke
				(width 0.05)
				(type default)
			)
			(fill no)
			(layer "F.CrtYd")
		)
		(fp_text user "Author: Antmicro"
			(at -0.4 3.901 0)
			(layer "F.Fab")
			(effects
				(font
					(size 0.7 0.7)
					(thickness 0.15)
				)
				(justify left bottom)
			)
		)
		(fp_text user "${REFERENCE}"
			(at -0.4 2.7 0)
			(layer "F.Fab")
			(effects
				(font
					(size 0.7 0.7)
					(thickness 0.15)
				)
				(justify left bottom)
			)
		)
		(fp_text user "License: Apache-2.0"
			(at -0.4 5.101 0)
			(layer "F.Fab")
			(effects
				(font
					(size 0.7 0.7)
					(thickness 0.15)
				)
				(justify left bottom)
			)
		)
		(pad "1" smd circle
			(at 0 0)
			(size 0.75 0.75)
			(layers "F.Cu" "F.Mask")
			(net 259 "/Compute module/Pf_5V.SCL")
			(pinfunction "1")
			(pintype "passive")
		)
	)
	(footprint "antmicro-footprints:SOT-23-3"
		(layer "F.Cu")
		(at 67.857962 146.0765)
		(property "Reference" "Q206"
			(at -1.89 1.565 90)
			(layer "F.SilkS")
			(effects
				(font
					(size 0.7 0.7)
					(thickness 0.15)
				)
				(justify left bottom)
			)
		)
		(property "Value" "SSM3J332R"
			(at -1.9 2.7 0)
			(layer "F.Fab")
			(effects
				(font
					(size 0.7 0.7)
					(thickness 0.15)
				)
				(justify left bottom)
			)
		)
		(property "Datasheet" "https://www.mouser.com/datasheet/2/408/SSM3J332R_datasheet_en_20181015-1150575.pdf"
			(at 0 0 0)
			(layer "F.Fab")
			(hide yes)
			(effects
				(font
					(size 1.27 1.27)
					(thickness 0.15)
				)
			)
		)
		(property "MPN" "SSM3J332R,LF"
			(at 0 0 0)
			(unlocked yes)
			(layer "F.Fab")
			(hide yes)
			(effects
				(font
					(size 1 1)
					(thickness 0.15)
				)
			)
		)
		(property "Manufacturer" "Toshiba"
			(at 0 0 0)
			(unlocked yes)
			(layer "F.Fab")
			(hide yes)
			(effects
				(font
					(size 1 1)
					(thickness 0.15)
				)
			)
		)
		(property "Author" "Antmicro"
			(at 0 0 0)
			(unlocked yes)
			(layer "F.Fab")
			(hide yes)
			(effects
				(font
					(size 1 1)
					(thickness 0.15)
				)
			)
		)
		(property "License" "Apache-2.0"
			(at 0 0 0)
			(unlocked yes)
			(layer "F.Fab")
			(hide yes)
			(effects
				(font
					(size 1 1)
					(thickness 0.15)
				)
			)
		)
		(sheetname "/Compute module/")
		(sheetfile "compute-module.kicad_sch")
		(attr smd)
		(fp_line
			(start -1.45 -1.35)
			(end -0.85 -1.35)
			(stroke
				(width 0.15)
				(type solid)
			)
			(layer "F.SilkS")
		)
		(fp_line
			(start -0.85 -1.35)
			(end -0.7 -1.5)
			(stroke
				(width 0.15)
				(type solid)
			)
			(layer "F.SilkS")
		)
		(fp_line
			(start -0.7 1.5)
			(end -0.7 1.35)
			(stroke
				(width 0.15)
				(type solid)
			)
			(layer "F.SilkS")
		)
		(fp_line
			(start 0.7 -1.5)
			(end -0.7 -1.5)
			(stroke
				(width 0.15)
				(type solid)
			)
			(layer "F.SilkS")
		)
		(fp_line
			(start 0.7 -0.4)
			(end 0.7 -1.5)
			(stroke
				(width 0.15)
				(type solid)
			)
			(layer "F.SilkS")
		)
		(fp_line
			(start 0.7 0.4)
			(end 0.7 1.5)
			(stroke
				(width 0.15)
				(type solid)
			)
			(layer "F.SilkS")
		)
		(fp_line
			(start 0.7 1.5)
			(end -0.7 1.5)
			(stroke
				(width 0.15)
				(type solid)
			)
			(layer "F.SilkS")
		)
		(fp_line
			(start -1.75 -0.5)
			(end -1.75 -1.4)
			(stroke
				(width 0.05)
				(type solid)
			)
			(layer "F.CrtYd")
		)
		(fp_line
			(start -1.75 0.5)
			(end -0.85 0.5)
			(stroke
				(width 0.05)
				(type solid)
			)
			(layer "F.CrtYd")
		)
		(fp_line
			(start -1.75 1.4)
			(end -1.75 0.5)
			(stroke
				(width 0.05)
				(type solid)
			)
			(layer "F.CrtYd")
		)
		(fp_line
			(start -0.9 -1.6)
			(end -0.9 -1.4)
			(stroke
				(width 0.05)
				(type solid)
			)
			(layer "F.CrtYd")
		)
		(fp_line
			(start -0.9 -1.6)
			(end 0.825 -1.6)
			(stroke
				(width 0.05)
				(type solid)
			)
			(layer "F.CrtYd")
		)
		(fp_line
			(start -0.9 -1.4)
			(end -1.75 -1.4)
			(stroke
				(width 0.05)
				(type solid)
			)
			(layer "F.CrtYd")
		)
		(fp_line
			(start -0.85 -0.5)
			(end -1.75 -0.5)
			(stroke
				(width 0.05)
				(type solid)
			)
			(layer "F.CrtYd")
		)
		(fp_line
			(start -0.85 0.5)
			(end -0.85 -0.5)
			(stroke
				(width 0.05)
				(type solid)
			)
			(layer "F.CrtYd")
		)
		(fp_line
			(start -0.85 1.4)
			(end -1.75 1.4)
			(stroke
				(width 0.05)
				(type solid)
			)
			(layer "F.CrtYd")
		)
		(fp_line
			(start -0.85 1.65)
			(end -0.85 1.4)
			(stroke
				(width 0.05)
				(type solid)
			)
			(layer "F.CrtYd")
		)
		(fp_line
			(start 0.825 -1.6)
			(end 0.825 -0.45)
			(stroke
				(width 0.05)
				(type solid)
			)
			(layer "F.CrtYd")
		)
		(fp_line
			(start 0.825 -0.45)
			(end 1.75 -0.45)
			(stroke
				(width 0.05)
				(type solid)
			)
			(layer "F.CrtYd")
		)
		(fp_line
			(start 0.85 0.45)
			(end 0.85 1.65)
			(stroke
				(width 0.05)
				(type solid)
			)
			(layer "F.CrtYd")
		)
		(fp_line
			(start 0.85 1.65)
			(end -0.85 1.65)
			(stroke
				(width 0.05)
				(type solid)
			)
			(layer "F.CrtYd")
		)
		(fp_line
			(start 1.75 -0.45)
			(end 1.75 0.45)
			(stroke
				(width 0.05)
				(type solid)
			)
			(layer "F.CrtYd")
		)
		(fp_line
			(start 1.75 0.45)
			(end 0.85 0.45)
			(stroke
				(width 0.05)
				(type solid)
			)
			(layer "F.CrtYd")
		)
		(fp_line
			(start -0.712 -1.325)
			(end -0.712 1.523)
			(stroke
				(width 0.15)
				(type solid)
			)
			(layer "F.Fab")
		)
		(fp_line
			(start -0.712 1.519)
			(end 0.688 1.519)
			(stroke
				(width 0.15)
				(type solid)
			)
			(layer "F.Fab")
		)
		(fp_line
			(start -0.437 -1.526)
			(end -0.712 -1.325)
			(stroke
				(width 0.15)
				(type solid)
			)
			(layer "F.Fab")
		)
		(fp_line
			(start -0.437 -1.526)
			(end 0.688 -1.526)
			(stroke
				(width 0.15)
				(type solid)
			)
			(layer "F.Fab")
		)
		(fp_line
			(start 0.688 1.519)
			(end 0.688 -1.52)
			(stroke
				(width 0.15)
				(type solid)
			)
			(layer "F.Fab")
		)
		(fp_text user "${REFERENCE}"
			(at -1.837 4 0)
			(layer "F.Fab")
			(effects
				(font
					(size 0.7 0.7)
					(thickness 0.15)
				)
				(justify left bottom)
			)
		)
		(fp_text user "License: Apache-2.0"
			(at -1.8 6.8 0)
			(layer "F.Fab")
			(effects
				(font
					(size 0.7 0.7)
					(thickness 0.15)
				)
				(justify left bottom)
			)
		)
		(fp_text user "Author: Antmicro"
			(at -1.837 5.3 0)
			(layer "F.Fab")
			(effects
				(font
					(size 0.7 0.7)
					(thickness 0.15)
				)
				(justify left bottom)
			)
		)
		(pad "1" smd roundrect
			(at -1.1 -0.951)
			(size 1 0.6)
			(layers "F.Cu" "F.Mask" "F.Paste")
			(roundrect_rratio 0.15)
			(net 491 "Net-(Q206-G)")
			(pinfunction "G")
			(pintype "input")
		)
		(pad "2" smd roundrect
			(at -1.1 0.949)
			(size 1 0.6)
			(layers "F.Cu" "F.Mask" "F.Paste")
			(roundrect_rratio 0.15)
			(net 9 "+3V3")
			(pinfunction "S")
			(pintype "passive")
		)
		(pad "3" smd roundrect
			(at 1.1 -0.0005)
			(size 1 0.6)
			(layers "F.Cu" "F.Mask" "F.Paste")
			(roundrect_rratio 0.15)
			(net 468 "Net-(D202-A)")
			(pinfunction "D")
			(pintype "passive")
		)
	)
)
